#ISCELL
  mstr_misc dns *
  *
#ISCELL
  pure_quanta quanta_title_block_c *
  *
#ISCELL
  standard offpage *
  page260_i1
#CELL
  pure_quanta q_res *
  page260_i10
#CELL
  pure_quanta q_res *
  page260_i100
#ISCELL
  logical_power universal_gnd *
  page260_i101
#ISCELL
  standard offpage *
  page260_i102
#ISCELL
  logical_power universal_gnd *
  page260_i103
#ISCELL
  logical_power vcc15 *
  page260_i104
#ISCELL
  logical_power universal_gnd *
  page260_i105
#CELL
  pure_quanta q_res *
  page260_i106
#ISCELL
  standard offpage *
  page260_i107
#ISCELL
  standard offpage *
  page260_i108
#CELL
  pure_quanta q_res *
  page260_i109
#CELL
  pure_quanta q_res *
  page260_i11
#CELL
  pure_quanta q_cap *
  page260_i110
#ISCELL
  logical_power vcc15 *
  page260_i12
#CELL
  pure_quanta q_res *
  page260_i13
#CELL
  pure_quanta q_res *
  page260_i14
#ISCELL
  logical_power universal_gnd *
  page260_i15
#ISCELL
  logical_power vcc15 *
  page260_i16
#CELL
  pure_quanta q_res *
  page260_i17
#CELL
  pure_quanta q_res *
  page260_i18
#CELL
  pure_quanta q_res *
  page260_i19
#ISCELL
  standard offpage *
  page260_i2
#CELL
  pure_quanta q_cap *
  page260_i20
#CELL
  pure_quanta q_res *
  page260_i21
#CELL
  pure_quanta q_cap *
  page260_i22
#CELL
  pure_quanta q_cap *
  page260_i23
#ISCELL
  standard offpage *
  page260_i24
#ISCELL
  standard offpage *
  page260_i25
#ISCELL
  standard offpage *
  page260_i26
#ISCELL
  standard offpage *
  page260_i27
#ISCELL
  logical_power vcc15 *
  page260_i28
#ISCELL
  standard offpage *
  page260_i29
#ISCELL
  standard offpage *
  page260_i3
#ISCELL
  standard offpage *
  page260_i30
#ISCELL
  standard offpage *
  page260_i31
#ISCELL
  standard offpage *
  page260_i32
#ISCELL
  standard offpage *
  page260_i33
#ISCELL
  standard offpage *
  page260_i34
#ISCELL
  standard offpage *
  page260_i35
#CELL
  pure_quanta q_res *
  page260_i36
#CELL
  pure_quanta q_res *
  page260_i37
#CELL
  pure_quanta q_res *
  page260_i38
#CELL
  pure_quanta q_short *
  page260_i39
#ISCELL
  logical_power universal_gnd *
  page260_i4
#CELL
  pure_quanta q_res *
  page260_i40
#ISCELL
  logical_power vcc15 *
  page260_i41
#CELL
  pure_quanta q_res *
  page260_i42
#CELL
  pure_quanta q_short *
  page260_i43
#CELL
  pure_quanta q_res *
  page260_i44
#ISCELL
  logical_power universal_gnd *
  page260_i45
#ISCELL
  logical_power vcc15 *
  page260_i46
#CELL
  pure_quanta q_res *
  page260_i47
#CELL
  pure_quanta q_cap *
  page260_i48
#CELL
  pure_quanta q_res *
  page260_i49
#ISCELL
  logical_power universal_gnd *
  page260_i5
#CELL
  pure_quanta q_cap *
  page260_i50
#CELL
  pure_quanta q_res *
  page260_i51
#CELL
  pure_quanta q_res *
  page260_i52
#CELL
  pure_quanta q_res *
  page260_i53
#ISCELL
  logical_power vcc15 *
  page260_i54
#CELL
  pure_quanta q_res *
  page260_i55
#CELL
  pure_quanta q_res *
  page260_i56
#CELL
  pure_quanta q_res *
  page260_i57
#CELL
  pure_quanta q_res *
  page260_i58
#CELL
  pure_quanta q_res *
  page260_i59
#CELL
  pure_quanta q_cap *
  page260_i60
#CELL
  pure_quanta q_cap *
  page260_i61
#ISCELL
  logical_power universal_gnd *
  page260_i62
#CELL
  pure_quanta q_cap *
  page260_i63
#ISCELL
  logical_power universal_gnd *
  page260_i64
#CELL
  pure_quanta isl69260irazt *
  page260_i65
#ISCELL
  logical_power universal_gnd *
  page260_i66
#ISCELL
  logical_power universal_gnd *
  page260_i67
#ISCELL
  logical_power universal_gnd *
  page260_i68
#CELL
  pure_quanta q_cap *
  page260_i69
#CELL
  pure_quanta q_res *
  page260_i7
#ISCELL
  logical_power universal_gnd *
  page260_i70
#CELL
  pure_quanta q_res *
  page260_i71
#ISCELL
  logical_power universal_gnd *
  page260_i72
#CELL
  pure_quanta q_cap *
  page260_i73
#ISCELL
  standard offpage *
  page260_i74
#ISCELL
  standard offpage *
  page260_i75
#CELL
  pure_quanta q_res *
  page260_i76
#ISCELL
  standard offpage *
  page260_i77
#CELL
  pure_quanta q_res *
  page260_i78
#CELL
  pure_quanta q_res *
  page260_i79
#ISCELL
  logical_power vcc15 *
  page260_i8
#ISCELL
  logical_power universal_gnd *
  page260_i80
#ISCELL
  logical_power vcc15 *
  page260_i81
#ISCELL
  logical_power universal_gnd *
  page260_i82
#ISCELL
  logical_power universal_gnd *
  page260_i83
#CELL
  pure_quanta q_res *
  page260_i84
#CELL
  pure_quanta q_res *
  page260_i85
#CELL
  pure_quanta q_res *
  page260_i86
#CELL
  pure_quanta q_res *
  page260_i87
#ISCELL
  logical_power universal_gnd *
  page260_i88
#ISCELL
  logical_power universal_gnd *
  page260_i89
#CELL
  pure_quanta q_res *
  page260_i9
#ISCELL
  logical_power universal_gnd *
  page260_i90
#ISCELL
  logical_power universal_gnd *
  page260_i91
#CELL
  pure_quanta q_cap *
  page260_i92
#ISCELL
  standard offpage *
  page260_i93
#ISCELL
  standard offpage *
  page260_i94
#CELL
  pure_quanta q_cap *
  page260_i95
#ISCELL
  standard offpage *
  page260_i96
#ISCELL
  standard offpage *
  page260_i97
#CELL
  pure_quanta q_cap *
  page260_i98
#CELL
  pure_quanta q_cap *
  page260_i99
